# BASEBOARD_FAB2 (Tioga Pass) — schematic parts with pin connectivity, parts 4665–4665 of 4751; source: Cadence DE-HDL packaged netlist (pstxprt.dat, pstxnet.dat, pstchip.dat)

U5D1  SKX_EXT_B  IC  pkg BGA1  page 21  (pins 679-1017 of 3647)
  AW16  TEST_8  BI  = TP_CPU0_TEST_8
  AW18  TXT_AGENT  IN  = PU_CPU0_TXT_AGENT
  AW20  TEST_9  BI  = TP_CPU0_TEST_9
  AW22  TEST_10  BI  = TP_CPU0_TEST_10
  AW24  BCLK0_DP  IN  = CLK_100M_CPU0_BCLK0_DP
  AW26  VCCIO(79)  POWER  = PVCCIO_CPU0
  AW60  VCCIN(231)  POWER  = PVCCIN_CPU0
  AW62  VSS(692)  GROUND  = GND
  AW64  RSVD(184)  BI  = TP_CPU0_RSVD_184
  AW66  VSS(691)  GROUND  = GND
  AW68  VSS(690)  GROUND  = GND
  AW70  VSS(689)  GROUND  = GND
  AW72  VSS(688)  GROUND  = GND
  AW74  VSS(687)  GROUND  = GND
  AW76  RSVD(183)  BI  = TP_CPU0_RSVD_183
  AW78  VSS(686)  GROUND  = GND
  AW80  DDR1_DQ(4)  BI  = M_B_DQ<4>
  AW82  VSS(685)  GROUND  = GND
  AW84  VSS(684)  GROUND  = GND
  AW86  VCCINPMAX(0)  POWER  = VSENSE_VCCINR2PMAX_CPU0
  AY3  UPI0_TX_DP(16)  OUT  = UPI_CPU0_CPU1_P0P0_DP<3>
  AY5  VSS(683)  GROUND  = GND
  AY7  UPI0_RX_DP(13)  IN  = UPI_CPU1_CPU0_P0P0_DP<6>
  AY9  UPI0_RX_DN(17)  IN  = UPI_CPU1_CPU0_P0P0_DN<2>
  AY11  VCCIO(36)  POWER  = PVCCIO_CPU0
  AY13  TEST_11  BI  = TP_CPU0_RSVD_TEST_11
  AY15  VSS(682)  GROUND  = GND
  AY17  VSS(681)  GROUND  = GND
  AY19  TEST_12  BI  = PD_CPU0_TEST12
  AY21  VSS(680)  GROUND  = GND
  AY23  VSS(679)  GROUND  = GND
  AY25  VSS(678)  GROUND  = GND
  AY27  VCCIO(78)  POWER  = PVCCIO_CPU0
  AY61  VCCIN(230)  POWER  = PVCCIN_CPU0
  AY63  VSS(677)  GROUND  = GND
  AY65  RSVD(182)  BI  = TP_CPU0_RSVD_182
  AY67  RSVD(181)  BI  = TP_CPU0_RSVD_181
  AY69  DDR2_ECC(3)  BI  = M_C_ECC<3>
  AY71  DDR2_DQS_DP(8)  BI  = M_C_DQS_DP<8>
  AY73  DDR2_ECC(5)  BI  = M_C_ECC<5>
  AY75  RSVD(180)  BI  = TP_CPU0_RSVD_180
  AY77  RSVD(179)  BI  = TP_CPU0_RSVD_179
  AY79  VSS(676)  GROUND  = GND
  AY81  VSS(675)  GROUND  = GND
  AY83  RSVD(255)  BI  = TP_CPU0_RSVD_255
  AY85  VSS_VCCIN_SENSE  POWER  = VSENSE_PVCCIN_CPU0_SKT_VRTN
  B3  RSVD(299)  BI  = TP_CPU0_RSVD_299
  B5  VSS(1250)  GROUND  = GND
  B7  RSVD(298)  BI  = TP_CPU0_RSVD_298
  B9  VSS(1253)  GROUND  = GND
  B11  CD_VPP(0)  POWER  = PVPP_ABC
  B13  RSVD(296)  BI  = P1V8_MCP_CPU0
  B15  RSVD(295)  BI  = P1V8_MCP_CPU0
  B17  RSVD(294)  BI  = P1V8_MCP_CPU0
  B25  VSS(1180)  GROUND  = GND
  B27  DDR1_DQ(54)  BI  = M_B_DQ<54>
  B29  DDR1_DQ(49)  BI  = M_B_DQ<49>
  B31  VSS(1179)  GROUND  = GND
  B33  DDR1_DQ(46)  BI  = M_B_DQ<46>
  B35  DDR1_DQ(41)  BI  = M_B_DQ<41>
  B37  VSS(1178)  GROUND  = GND
  B39  DDR0_DQ(38)  BI  = M_A_DQ<38>
  B41  DDR0_DQ(33)  BI  = M_A_DQ<33>
  B43  VSS(1251)  GROUND  = GND
  B47  VCCD012(51)  POWER  = PVDDQ_ABC
  B49  VCCD012(0)  POWER  = PVDDQ_ABC
  B51  DDR0_CS_N(4)  OUT  = M_A_CS_N<4>
  B53  VCCD012(1)  POWER  = PVDDQ_ABC
  B55  DDR0_CLK_DP(1)  OUT  = M_A_CLK_DP<1>
  B57  DDR0_CLK_DP(3)  OUT  = M_A_CLK_DP<3>
  B59  VCCD012(2)  POWER  = PVDDQ_ABC
  B61  DDR0_ALERT_N  IN  = M_A_ALERT_N
  B63  DDR0_CKE(2)  OUT  = M_A_CKE<2>
  B71  VSS(1177)  GROUND  = GND
  B73  DDR1_DQS_DN(12)  BI  = M_B_DQS_DN<12>
  B75  VSS(1176)  GROUND  = GND
  B77  RSVD(293)  BI  = TP_CPU0_RSVD_293
  B79  VSS(1249)  GROUND  = GND
  B81  RSVD(292)  BI  = TP_CPU0_RSVD_292
  BA2  VSS(674)  GROUND  = GND
  BA4  UPI0_TX_DN(16)  OUT  = UPI_CPU0_CPU1_P0P0_DN<3>
  BA6  VSS(673)  GROUND  = GND
  BA8  UPI0_RX_DN(13)  IN  = UPI_CPU1_CPU0_P0P0_DN<6>
  BA10  UPI0_RX_DP(19)  IN  = UPI_CPU1_CPU0_P0P0_DP<0>
  BA12  VSS(672)  GROUND  = GND
  BA14  RSVD(178)  BI  = TP_CPU0_RSVD_178
  BA16  RSVD(177)  BI  = TP_CPU0_RSVD_177
  BA18  RSVD(176)  BI  = TP_CPU0_RSVD_176
  BA20  BIST_ENABLE  IN  = PD_CPU0_BIST_ENABLE
  BA22  RSVD(175)  BI  = TP_CPU0_RSVD_175
  BA24  VCCIO(35)  POWER  = PVCCIO_CPU0
  BA26  VCCIO(77)  POWER  = PVCCIO_CPU0
  BA60  VCCIN(229)  POWER  = PVCCIN_CPU0
  BA62  VSS(671)  GROUND  = GND
  BA64  RSVD(174)  BI  = TP_CPU0_RSVD_174
  BA66  RSVD(173)  BI  = TP_CPU0_RSVD_173
  BA68  VSS(670)  GROUND  = GND
  BA70  DDR2_ECC(7)  BI  = M_C_ECC<7>
  BA72  DDR2_ECC(1)  BI  = M_C_ECC<1>
  BA74  VSS(669)  GROUND  = GND
  BA76  RSVD(172)  BI  = TP_CPU0_RSVD_172
  BA78  RSVD(171)  BI  = TP_CPU0_RSVD_171
  BA80  VSS(668)  GROUND  = GND
  BA82  RSVD(170)  BI  = TP_CPU0_RSVD_170
  BA84  VSS(667)  GROUND  = GND
  BA86  VCCIN_SENSE  BI  = VSENSE_PVCCIN_CPU0_SKT_VSEN
  BB3  UPI0_TX_DN(17)  OUT  = UPI_CPU0_CPU1_P0P0_DN<2>
  BB5  VCCIO(34)  POWER  = PVCCIO_CPU0
  BB7  UPI0_RX_DP(14)  IN  = UPI_CPU1_CPU0_P0P0_DP<5>
  BB9  UPI0_RX_DP(17)  IN  = UPI_CPU1_CPU0_P0P0_DP<2>
  BB11  UPI0_RX_DN(19)  IN  = UPI_CPU1_CPU0_P0P0_DN<0>
  BB13  RSVD(169)  BI  = TP_CPU0_RSVD_169
  BB15  RSVD(168)  BI  = TP_CPU0_RSVD_168
  BB17  RSVD(167)  BI  = TP_CPU0_RSVD_167
  BB19  VSS(666)  GROUND  = GND
  BB21  RSVD(166)  BI  = TP_CPU0_RSVD_166
  BB23  VSS(665)  GROUND  = GND
  BB25  RSVD(165)  BI  = CLK_100M_CPU0_RC_REFCLK1_DN
  BB27  VCCIO(76)  POWER  = PVCCIO_CPU0
  BB61  VCCIN(228)  POWER  = PVCCIN_CPU0
  BB63  VSS(664)  GROUND  = GND
  BB65  RSVD(164)  BI  = TP_CPU0_RSVD_164
  BB67  RSVD(163)  BI  = TP_CPU0_RSVD_163
  BB69  VSS(663)  GROUND  = GND
  BB71  DDR2_DQS_DN(8)  BI  = M_C_DQS_DN<8>
  BB73  VSS(662)  GROUND  = GND
  BB75  VSS(661)  GROUND  = GND
  BB77  VSS(660)  GROUND  = GND
  BB79  VSS(659)  GROUND  = GND
  BB81  VSS(658)  GROUND  = GND
  BB83  VSS(657)  GROUND  = GND
  BB85  VCCIN(227)  POWER  = PVCCIN_CPU0
  BC2  UPI0_TX_DP(17)  OUT  = UPI_CPU0_CPU1_P0P0_DP<2>
  BC4  VSS(656)  GROUND  = GND
  BC6  UPI0_RX_DN(14)  IN  = UPI_CPU1_CPU0_P0P0_DN<5>
  BC8  VSS(655)  GROUND  = GND
  BC10  UPI0_RX_DP(18)  IN  = UPI_CPU1_CPU0_P0P0_DP<1>
  BC12  VSS(654)  GROUND  = GND
  BC14  RSVD(162)  BI  = TP_CPU0_RSVD_162
  BC16  VSS(653)  GROUND  = GND
  BC18  RSVD(161)  BI  = TP_CPU0_RSVD_161
  BC20  RSVD(160)  BI  = TP_CPU0_RSVD_160
  BC22  RSVD(159)  BI  = TP_CPU0_RSVD_159
  BC24  PWRGOOD  IN  = PWRGD_CPU0_G
  BC26  VCCIO(75)  POWER  = PVCCIO_CPU0
  BC60  VCCIN(226)  POWER  = PVCCIN_CPU0
  BC62  VCCIN(225)  POWER  = PVCCIN_CPU0
  BC64  RSVD(158)  BI  = TP_CPU0_RSVD_158
  BC66  RSVD(157)  BI  = TP_CPU0_RSVD_157
  BC68  RSVD(156)  BI  = TP_CPU0_RSVD_156
  BC70  VSS(652)  GROUND  = GND
  BC72  VSS(651)  GROUND  = GND
  BC74  VSS(650)  GROUND  = GND
  BC76  VSS(649)  GROUND  = GND
  BC78  VSS(648)  GROUND  = GND
  BC80  VSS(647)  GROUND  = GND
  BC82  VSS(646)  GROUND  = GND
  BC84  VCCIN(224)  POWER  = PVCCIN_CPU0
  BD3  UPI0_TX_DP(18)  OUT  = UPI_CPU0_CPU1_P0P0_DP<1>
  BD5  VSS(645)  GROUND  = GND
  BD7  UPI0_RX_DN(15)  IN  = UPI_CPU1_CPU0_P0P0_DN<4>
  BD9  UPI0_RX_DN(18)  IN  = UPI_CPU1_CPU0_P0P0_DN<1>
  BD11  VSS(644)  GROUND  = GND
  BD13  CD_VCC_CORE(12)  POWER  = PVCCMCP_CPU0
  BD15  VSS(643)  GROUND  = GND
  BD17  RSVD(155)  BI  = TP_CPU0_RSVD_155
  BD19  RSVD(154)  BI  = TP_CPU0_RSVD_154
  BD21  VSS(642)  GROUND  = GND
  BD23  BMCINIT  IN  = H_CPU0_BMCINIT
  BD25  RSVD(153)  BI  = CLK_100M_CPU0_RC_REFCLK1_DP
  BD27  VSS(641)  GROUND  = GND
  BD61  VCCIN(223)  POWER  = PVCCIN_CPU0
  BD63  VSS(640)  GROUND  = GND
  BD65  RSVD(152)  BI  = TP_CPU0_RSVD_152
  BD67  RSVD(151)  BI  = TP_CPU0_RSVD_151
  BD69  RSVD(150)  BI  = TP_CPU0_RSVD_150
  BD71  VSS(639)  GROUND  = GND
  BD73  VCCIN(222)  POWER  = PVCCIN_CPU0
  BD75  VCCIN(221)  POWER  = PVCCIN_CPU0
  BD77  VCCIN(220)  POWER  = PVCCIN_CPU0
  BD79  VCCIN(219)  POWER  = PVCCIN_CPU0
  BD81  VCCIN(218)  POWER  = PVCCIN_CPU0
  BD83  VCCIN(217)  POWER  = PVCCIN_CPU0
  BD85  VCCIN(216)  POWER  = PVCCIN_CPU0
  BE4  VSS(638)  GROUND  = GND
  BE6  VSS(637)  GROUND  = GND
  BE8  VSS(636)  GROUND  = GND
  BE10  VSS(635)  GROUND  = GND
  BE12  CD_VCC_CORE(11)  POWER  = PVCCMCP_CPU0
  BE14  CD_VCC_CORE(10)  POWER  = PVCCMCP_CPU0
  BE16  CD_HFI_REFCLK_DN  IN  = CLK_156M_OSC_CPU0_HFI_DN
  BE18  RSVD(149)  BI  = TP_CPU0_RSVD_149
  BE20  RSVD(148)  BI  = TP_CPU0_RSVD_148
  BE22  RSVD(147)  BI  = TP_CPU0_RSVD_147
  BE24  VCCIO(7)  POWER  = PVCCIO_CPU0
  BE26  VSS(634)  GROUND  = GND
  BE60  VCCIN(215)  POWER  = PVCCIN_CPU0
  BE62  VCCIN(214)  POWER  = PVCCIN_CPU0
  BE64  VSS(633)  GROUND  = GND
  BE66  VSS(632)  GROUND  = GND
  BE68  VSS(631)  GROUND  = GND
  BE70  VSS(630)  GROUND  = GND
  BE72  VCCIN(213)  POWER  = PVCCIN_CPU0
  BE74  VCCIN(212)  POWER  = PVCCIN_CPU0
  BE76  VCCIN(211)  POWER  = PVCCIN_CPU0
  BE78  VCCIN(210)  POWER  = PVCCIN_CPU0
  BE80  VCCIN(209)  POWER  = PVCCIN_CPU0
  BE82  VCCIN(208)  POWER  = PVCCIN_CPU0
  BE84  VCCIN(207)  POWER  = PVCCIN_CPU0
  BF3  UPI0_TX_DN(18)  OUT  = UPI_CPU0_CPU1_P0P0_DN<1>
  BF5  VSS_VCCIO_SENSE  POWER  = VSENSE_PVCCIO_CPU0_SKT_VRTN
  BF7  UPI0_RX_DP(15)  IN  = UPI_CPU1_CPU0_P0P0_DP<4>
  BF9  VSS(629)  GROUND  = GND
  BF11  CD_VCC_CORE(9)  POWER  = PVCCMCP_CPU0
  BF13  CD_VCC_CORE(8)  POWER  = PVCCMCP_CPU0
  BF15  VSS(628)  GROUND  = GND
  BF17  VSS(627)  GROUND  = GND
  BF19  VSS(626)  GROUND  = GND
  BF21  RSVD(146)  BI  = TP_CPU0_RSVD_146
  BF23  VCCIO(32)  POWER  = PVCCIO_CPU0
  BF25  VSS(625)  GROUND  = GND
  BF27  VCCIO(94)  POWER  = PVCCIO_CPU0
  BF61  VCCIN(206)  POWER  = PVCCIN_CPU0
  BF63  VSS(624)  GROUND  = GND
  BF65  VSS(623)  GROUND  = GND
  BF67  VSS(622)  GROUND  = GND
  BF69  VSS(621)  GROUND  = GND
  BF71  VSS(620)  GROUND  = GND
  BF73  VCCIN(205)  POWER  = PVCCIN_CPU0
  BF75  VCCIN(204)  POWER  = PVCCIN_CPU0
  BF77  VCCIN(203)  POWER  = PVCCIN_CPU0
  BF79  VCCIN(202)  POWER  = PVCCIN_CPU0
  BF81  VCCIN(201)  POWER  = PVCCIN_CPU0
  BF83  VCCIN(200)  POWER  = PVCCIN_CPU0
  BF85  VCCIN(199)  POWER  = PVCCIN_CPU0
  BG4  UPI0_TX_DN(19)  OUT  = UPI_CPU0_CPU1_P0P0_DN<0>
  BG6  VSS(619)  GROUND  = GND
  BG8  VSS(618)  GROUND  = GND
  BG10  VSS(617)  GROUND  = GND
  BG12  CD_VCC_CORE(7)  POWER  = PVCCMCP_CPU0
  BG14  CD_VCC_CORE(6)  POWER  = PVCCMCP_CPU0
  BG16  CD_HFI_REFCLK_DP  IN  = CLK_156M_OSC_CPU0_HFI_DP
  BG18  RSVD(145)  BI  = TP_CPU0_RSVD_145
  BG20  RSVD(144)  BI  = TP_CPU0_RSVD_144
  BG22  VSS(616)  GROUND  = GND
  BG24  VSS(615)  GROUND  = GND
  BG26  VCCIO(93)  POWER  = PVCCIO_CPU0
  BG60  VCCIN(198)  POWER  = PVCCIN_CPU0
  BG62  VCCIN(197)  POWER  = PVCCIN_CPU0
  BG64  VCCIN(196)  POWER  = PVCCIN_CPU0
  BG66  VCCIN(195)  POWER  = PVCCIN_CPU0
  BG68  VCCIN(194)  POWER  = PVCCIN_CPU0
  BG70  VCCIN(193)  POWER  = PVCCIN_CPU0
  BG72  VSS(614)  GROUND  = GND
  BG74  VSS(613)  GROUND  = GND
  BG76  VSS(612)  GROUND  = GND
  BG78  VSS(611)  GROUND  = GND
  BG80  VSS(610)  GROUND  = GND
  BG82  VSS(609)  GROUND  = GND
  BG84  VCCIN(192)  POWER  = PVCCIN_CPU0
  BH3  UPI0_TX_DP(19)  OUT  = UPI_CPU0_CPU1_P0P0_DP<0>
  BH5  VCCIO_SENSE  POWER  = VSENSE_PVCCIO_CPU0_SKT_VSEN
  BH7  VSS(608)  GROUND  = GND
  BH9  VSS(607)  GROUND  = GND
  BH11  VSS(606)  GROUND  = GND
  BH13  CD_VCC_CORE(5)  POWER  = PVCCMCP_CPU0
  BH15  VSS(605)  GROUND  = GND
  BH17  VSS(141)  GROUND  = GND
  BH19  RSVD(143)  BI  = PVCCMCP_CPU0
  BH21  VSS(604)  GROUND  = GND
  BH23  CD_HFI1_I2CDAT  BI  = SMB_HFI1_CPU0_LVC2_SDA
  BH25  VCCIO(92)  POWER  = PVCCIO_CPU0
  BH27  VCCIO(91)  POWER  = PVCCIO_CPU0
  BH61  VCCIN(191)  POWER  = PVCCIN_CPU0
  BH63  VCCIN(190)  POWER  = PVCCIN_CPU0
  BH65  VCCIN(189)  POWER  = PVCCIN_CPU0
  BH67  VCCIN(188)  POWER  = PVCCIN_CPU0
  BH69  VCCIN(187)  POWER  = PVCCIN_CPU0
  BH71  VCCIN(186)  POWER  = PVCCIN_CPU0
  BH73  VCCIN(185)  POWER  = PVCCIN_CPU0
  BH75  VCCIN(184)  POWER  = PVCCIN_CPU0
  BH77  VCCIN(183)  POWER  = PVCCIN_CPU0
  BH79  VCCIN(182)  POWER  = PVCCIN_CPU0
  BH81  VCCIN(181)  POWER  = PVCCIN_CPU0
  BH83  VCCIN(180)  POWER  = PVCCIN_CPU0
  BJ4  VSS(603)  GROUND  = GND
  BJ6  VSS(602)  GROUND  = GND
  BJ8  PE2_RX_DP(14)  IN  = P3E_CPU0_PE2_SS_RXP<14>
  BJ10  PE2_RX_DP(15)  IN  = P3E_CPU0_PE2_SS_RXP<15>
  BJ12  CD_VCC_CORE(4)  POWER  = PVCCMCP_CPU0
  BJ14  CD_VCC_CORE(3)  POWER  = PVCCMCP_CPU0
  BJ16  RSVD(142)  BI  = PVCCMCP_CPU0
  BJ18  RSVD(141)  BI  = PVCCMCP_CPU0
  BJ20  RSVD(140)  BI  = PVCCMCP_CPU0
  BJ22  CD_HFI1_I2CCLK  BI  = SMB_HFI1_CPU0_LVC2_SCL
  BJ24  VCCIO(31)  POWER  = PVCCIO_CPU0
  BJ26  VCCIO(90)  POWER  = PVCCIO_CPU0
  BJ60  VCCIN(179)  POWER  = PVCCIN_CPU0
  BJ62  VCCIN(178)  POWER  = PVCCIN_CPU0
  BJ64  VCCIN(177)  POWER  = PVCCIN_CPU0
  BJ66  VCCIN(176)  POWER  = PVCCIN_CPU0
  BJ68  VCCIN(175)  POWER  = PVCCIN_CPU0
  BJ70  VCCIN(174)  POWER  = PVCCIN_CPU0
  BJ72  VCCIN(173)  POWER  = PVCCIN_CPU0
  BJ74  VCCIN(172)  POWER  = PVCCIN_CPU0
  BJ76  VCCIN(171)  POWER  = PVCCIN_CPU0
  BJ78  VCCIN(170)  POWER  = PVCCIN_CPU0
  BJ80  VCCIN(169)  POWER  = PVCCIN_CPU0
  BJ82  VCCIN(168)  POWER  = PVCCIN_CPU0
  BJ84  VCCIN(167)  POWER  = PVCCIN_CPU0
  BK3  VSS(601)  GROUND  = GND
  BK5  PE2_TX_DP(15)  OUT  = P3E_CPU0_PE2_SS_TXP<15>
  BK7  VSS(600)  GROUND  = GND
  BK9  PE2_RX_DN(15)  IN  = P3E_CPU0_PE2_SS_RXN<15>
  BK11  VSS(599)  GROUND  = GND
  BK13  CD_VCC_CORE(2)  POWER  = PVCCMCP_CPU0
  BK15  CD_VCC_CORE(1)  POWER  = PVCCMCP_CPU0
  BK17  RSVD(139)  BI  = PVCCMCP_CPU0
  BK19  VSS(598)  GROUND  = GND
  BK21  CD_HFI0_LED_N  OUT  = LED_HFI0_CPU0_N
  BK23  CD_HFI1_RESET_N  OUT  = RST_HFI1_CPU0_LVT2_N
  BK25  VCCIO(89)  POWER  = PVCCIO_CPU0
  BK27  VCCIO(88)  POWER  = PVCCIO_CPU0
  BK61  VCCIN(166)  POWER  = PVCCIN_CPU0
  BK63  VCCIN(165)  POWER  = PVCCIN_CPU0
  BK65  VCCIN(164)  POWER  = PVCCIN_CPU0
  BK67  VCCIN(163)  POWER  = PVCCIN_CPU0
  BK69  VCCIN(162)  POWER  = PVCCIN_CPU0
  BK71  VCCIN(161)  POWER  = PVCCIN_CPU0
  BK73  VCCIN(160)  POWER  = PVCCIN_CPU0
  BK75  VCCIN(159)  POWER  = PVCCIN_CPU0
  BK77  VCCIN(158)  POWER  = PVCCIN_CPU0
  BK79  VCCIN(157)  POWER  = PVCCIN_CPU0
  BK81  VCCIN(156)  POWER  = PVCCIN_CPU0
  BK83  VCCIN(155)  POWER  = PVCCIN_CPU0
  BL4  PE2_TX_DN(14)  OUT  = P3E_CPU0_PE2_SS_TXN<14>
  BL6  VSS(597)  GROUND  = GND
  BL8  PE2_RX_DN(14)  IN  = P3E_CPU0_PE2_SS_RXN<14>
  BL10  VSS(596)  GROUND  = GND
